# T6G (Grand Teton) — schematic parts with pin connectivity, parts 8081–8081 of 8303; source: Cadence DE-HDL packaged netlist (pstxprt.dat, pstxnet.dat, pstchip.dat)

U25  GENOA_SP5  SOCKET6096_13568-001 IO  pkg SOCKET6096_93-4X120-45XA  page 10  (pins 5713-6048 of 6096)
  R52  G1_RXN14  IN  = GMI_CPU1_G3_CPU0_G1_TX_DN<14>
  R53  G1_RXP14  IN  = GMI_CPU1_G3_CPU0_G1_TX_DP<14>
  R54  VSS_R54  POWER  = GND
  R55  MCA_DQS_H6  BI  = M_C_CPU0_SA_DQS_DP<6>
  R56  VSS_R56  POWER  = GND
  R57  MCA_DATA12  BI  = M_C_CPU0_SA_DQ<12>
  R58  VSS_R58  POWER  = GND
  R59  MDA_DQS_H6  BI  = M_D_CPU0_SA_DQS_DP<6>
  R60  MDA_DATA12  BI  = M_D_CPU0_SA_DQ<12>
  R61  VSS_R61  POWER  = GND
  R62  MBA_DQS_H6  BI  = M_B_CPU0_SA_DQS_DP<6>
  R63  VSS_R63  POWER  = GND
  R64  MBA_DATA12  BI  = M_B_CPU0_SA_DQ<12>
  R65  VSS_R65  POWER  = GND
  R66  MFA_DQS_H6  BI  = M_F_CPU0_SA_DQS_DP<6>
  R67  MFA_DATA12  BI  = M_F_CPU0_SA_DQ<12>
  R68  VSS_R68  POWER  = GND
  R69  MEA_DQS_H6  BI  = M_E_CPU0_SA_DQS_DP<6>
  R70  VSS_R70  POWER  = GND
  R71  MEA_DATA12  BI  = M_E_CPU0_SA_DQ<12>
  R72  VSS_R72  POWER  = GND
  R73  MAA_DQS_H6  BI  = M_A_CPU0_SA_DQS_DP<6>
  R74  MAA_DATA12  BI  = M_A_CPU0_SA_DQ<12>
  R75  VSS_R75  POWER  = GND
  T2  MGA_DATA14  BI  = M_G_CPU0_SA_DQ<14>
  T3  VSS_T3  POWER  = GND
  T4  MGA_DATA13  BI  = M_G_CPU0_SA_DQ<13>
  T5  VSS_T5  POWER  = GND
  T6  MKA_DATA14  BI  = M_K_CPU0_SA_DQ<14>
  T7  MKA_DATA13  BI  = M_K_CPU0_SA_DQ<13>
  T8  VSS_T8  POWER  = GND
  T9  MLA_DATA14  BI  = M_L_CPU0_SA_DQ<14>
  T10  VSS_T10  POWER  = GND
  T11  MLA_DATA13  BI  = M_L_CPU0_SA_DQ<13>
  T12  VSS_T12  POWER  = GND
  T13  MHA_DATA14  BI  = M_H_CPU0_SA_DQ<14>
  T14  MHA_DATA13  BI  = M_H_CPU0_SA_DQ<13>
  T15  VSS_T15  POWER  = GND
  T16  MJA_DATA14  BI  = M_J_CPU0_SA_DQ<14>
  T17  VSS_T17  POWER  = GND
  T18  MJA_DATA13  BI  = M_J_CPU0_SA_DQ<13>
  T19  VSS_T19  POWER  = GND
  T20  MIA_DATA14  BI  = M_I_CPU0_SA_DQ<14>
  T21  MIA_DATA13  BI  = M_I_CPU0_SA_DQ<13>
  T22  VSS_T22  POWER  = GND
  T23  VDDCR_CPU0_T23  POWER  = PVDDCR_CPU0_P0
  T24  VDDCR_CPU0_T24  POWER  = PVDDCR_CPU0_P0
  T25  VSS_T25  POWER  = GND
  T26  VDDCR_CPU0_T26  POWER  = PVDDCR_CPU0_P0
  T27  VDDCR_CPU0_T27  POWER  = PVDDCR_CPU0_P0
  T28  VSS_T28  POWER  = GND
  T29  VDDCR_CPU0_T29  POWER  = PVDDCR_CPU0_P0
  T30  VDDCR_CPU0_T30  POWER  = PVDDCR_CPU0_P0
  T31  VSS_T31  POWER  = GND
  T32  VDDCR_CPU0_T32  POWER  = PVDDCR_CPU0_P0
  T33  VDDCR_CPU0_T33  POWER  = PVDDCR_CPU0_P0
  T34  VSS_T34  POWER  = GND
  T35  \g3_txp14||sata36_txp\  OUT  = P5E_CPU0_G3_TX_DP<14>
  T36  \g3_txn14||sata36_txn\  OUT  = P5E_CPU0_G3_TX_DN<14>
  T37  VSS_T37  POWER  = GND
  T39  VSS_T39  POWER  = GND
  T40  G1_RXN1  IN  = GMI_CPU1_G3_CPU0_G1_TX_DN<1>
  T41  G1_RXP1  IN  = GMI_CPU1_G3_CPU0_G1_TX_DP<1>
  T42  VSS_T42  POWER  = GND
  T43  VDDCR_CPU0_T43  POWER  = PVDDCR_CPU0_P0
  T44  VDDCR_CPU0_T44  POWER  = PVDDCR_CPU0_P0
  T45  VSS_T45  POWER  = GND
  T46  VDDCR_CPU0_T46  POWER  = PVDDCR_CPU0_P0
  T47  VDDCR_CPU0_T47  POWER  = PVDDCR_CPU0_P0
  T48  VSS_T48  POWER  = GND
  T49  VDDCR_CPU0_T49  POWER  = PVDDCR_CPU0_P0
  T50  VDDCR_CPU0_T50  POWER  = PVDDCR_CPU0_P0
  T51  VSS_T51  POWER  = GND
  T52  VDDCR_CPU0_T52  POWER  = PVDDCR_CPU0_P0
  T53  VDDCR_CPU0_T53  POWER  = PVDDCR_CPU0_P0
  T54  VSS_T54  POWER  = GND
  T55  MCA_DATA13  BI  = M_C_CPU0_SA_DQ<13>
  T56  MCA_DATA14  BI  = M_C_CPU0_SA_DQ<14>
  T57  VSS_T57  POWER  = GND
  T58  MDA_DATA13  BI  = M_D_CPU0_SA_DQ<13>
  T59  VSS_T59  POWER  = GND
  T60  MDA_DATA14  BI  = M_D_CPU0_SA_DQ<14>
  T61  VSS_T61  POWER  = GND
  T62  MBA_DATA13  BI  = M_B_CPU0_SA_DQ<13>
  T63  MBA_DATA14  BI  = M_B_CPU0_SA_DQ<14>
  T64  VSS_T64  POWER  = GND
  T65  MFA_DATA13  BI  = M_F_CPU0_SA_DQ<13>
  T66  VSS_T66  POWER  = GND
  T67  MFA_DATA14  BI  = M_F_CPU0_SA_DQ<14>
  T68  VSS_T68  POWER  = GND
  T69  MEA_DATA13  BI  = M_E_CPU0_SA_DQ<13>
  T70  MEA_DATA14  BI  = M_E_CPU0_SA_DQ<14>
  T71  VSS_T71  POWER  = GND
  T72  MAA_DATA13  BI  = M_A_CPU0_SA_DQ<13>
  T73  VSS_T73  POWER  = GND
  T74  MAA_DATA14  BI  = M_A_CPU0_SA_DQ<14>
  U1  VSS_U1  POWER  = GND
  U2  MGA_DATA16  BI  = M_G_CPU0_SA_DQ<16>
  U3  MGA_DATA15  BI  = M_G_CPU0_SA_DQ<15>
  U4  VDDCR_SOC_U4  POWER  = PVDDCR_SOC_P0
  U5  MKA_DATA16  BI  = M_K_CPU0_SA_DQ<16>
  U6  VSS_U6  POWER  = GND
  U7  MKA_DATA15  BI  = M_K_CPU0_SA_DQ<15>
  U8  VSS_U8  POWER  = GND
  U9  MLA_DATA16  BI  = M_L_CPU0_SA_DQ<16>
  U10  MLA_DATA15  BI  = M_L_CPU0_SA_DQ<15>
  U11  VDDCR_SOC_U11  POWER  = PVDDCR_SOC_P0
  U12  MHA_DATA16  BI  = M_H_CPU0_SA_DQ<16>
  U13  VSS_U13  POWER  = GND
  U14  MHA_DATA15  BI  = M_H_CPU0_SA_DQ<15>
  U15  VSS_U15  POWER  = GND
  U16  MJA_DATA16  BI  = M_J_CPU0_SA_DQ<16>
  U17  MJA_DATA15  BI  = M_J_CPU0_SA_DQ<15>
  U18  VDDCR_SOC_U18  POWER  = PVDDCR_SOC_P0
  U19  MIA_DATA16  BI  = M_I_CPU0_SA_DQ<16>
  U20  VSS_U20  POWER  = GND
  U21  MIA_DATA15  BI  = M_I_CPU0_SA_DQ<15>
  U22  VSS_U22  POWER  = GND
  U23  \g3_txp0||sata20_txp\  OUT  = P5E_CPU0_G3_TX_DP<0>
  U24  \g3_txn0||sata20_txn\  OUT  = P5E_CPU0_G3_TX_DN<0>
  U25  VSS_U25  POWER  = GND
  U26  \g3_txp3||sata23_txp\  OUT  = P5E_CPU0_G3_TX_DP<3>
  U27  \g3_txn3||sata23_txn\  OUT  = P5E_CPU0_G3_TX_DN<3>
  U28  VSS_U28  POWER  = GND
  U29  \g3_txp9||sata31_txp\  OUT  = P5E_CPU0_G3_TX_DP<9>
  U30  \g3_txn9||sata31_txn\  OUT  = P5E_CPU0_G3_TX_DN<9>
  U31  VSS_U31  POWER  = GND
  U32  \g3_txp12||sata34_txp\  OUT  = P5E_CPU0_G3_TX_DP<12>
  U33  \g3_txn12||sata34_txn\  OUT  = P5E_CPU0_G3_TX_DN<12>
  U34  VSS_U34  POWER  = GND
  U35  VDDCR_CPU0_U35  POWER  = PVDDCR_CPU0_P0
  U36  VDDCR_CPU0_U36  POWER  = PVDDCR_CPU0_P0
  U40  VDDCR_CPU0_U40  POWER  = PVDDCR_CPU0_P0
  U41  VDDCR_CPU0_U41  POWER  = PVDDCR_CPU0_P0
  U42  VSS_U42  POWER  = GND
  U43  G1_RXN3  IN  = GMI_CPU1_G3_CPU0_G1_TX_DN<3>
  U44  G1_RXP3  IN  = GMI_CPU1_G3_CPU0_G1_TX_DP<3>
  U45  VSS_U45  POWER  = GND
  U46  G1_RXN6  IN  = GMI_CPU1_G3_CPU0_G1_TX_DN<6>
  U47  G1_RXP6  IN  = GMI_CPU1_G3_CPU0_G1_TX_DP<6>
  U48  VSS_U48  POWER  = GND
  U49  G1_RXN12  IN  = GMI_CPU1_G3_CPU0_G1_TX_DN<12>
  U50  G1_RXP12  IN  = GMI_CPU1_G3_CPU0_G1_TX_DP<12>
  U51  VSS_U51  POWER  = GND
  U52  G1_RXN15  IN  = GMI_CPU1_G3_CPU0_G1_TX_DN<15>
  U53  G1_RXP15  IN  = GMI_CPU1_G3_CPU0_G1_TX_DP<15>
  U54  VSS_U54  POWER  = GND
  U55  MCA_DATA15  BI  = M_C_CPU0_SA_DQ<15>
  U56  VSS_U56  POWER  = GND
  U57  MCA_DATA16  BI  = M_C_CPU0_SA_DQ<16>
  U58  VDDIO_U58  POWER  = PVDDIO_P0
  U59  MDA_DATA15  BI  = M_D_CPU0_SA_DQ<15>
  U60  MDA_DATA16  BI  = M_D_CPU0_SA_DQ<16>
  U61  VSS_U61  POWER  = GND
  U62  MBA_DATA15  BI  = M_B_CPU0_SA_DQ<15>
  U63  VSS_U63  POWER  = GND
  U64  MBA_DATA16  BI  = M_B_CPU0_SA_DQ<16>
  U65  VDDIO_U65  POWER  = PVDDIO_P0
  U66  MFA_DATA15  BI  = M_F_CPU0_SA_DQ<15>
  U67  MFA_DATA16  BI  = M_F_CPU0_SA_DQ<16>
  U68  VSS_U68  POWER  = GND
  U69  MEA_DATA15  BI  = M_E_CPU0_SA_DQ<15>
  U70  VSS_U70  POWER  = GND
  U71  MEA_DATA16  BI  = M_E_CPU0_SA_DQ<16>
  U72  VDDIO_U72  POWER  = PVDDIO_P0
  U73  MAA_DATA15  BI  = M_A_CPU0_SA_DQ<15>
  U74  MAA_DATA16  BI  = M_A_CPU0_SA_DQ<16>
  U75  VSS_U75  POWER  = GND
  V2  MGA_DATA18  BI  = M_G_CPU0_SA_DQ<18>
  V3  VSS_V3  POWER  = GND
  V4  MGA_DATA17  BI  = M_G_CPU0_SA_DQ<17>
  V5  VSS_V5  POWER  = GND
  V6  MKA_DATA18  BI  = M_K_CPU0_SA_DQ<18>
  V7  MKA_DATA17  BI  = M_K_CPU0_SA_DQ<17>
  V8  VSS_V8  POWER  = GND
  V9  MLA_DATA18  BI  = M_L_CPU0_SA_DQ<18>
  V10  VSS_V10  POWER  = GND
  V11  MLA_DATA17  BI  = M_L_CPU0_SA_DQ<17>
  V12  VSS_V12  POWER  = GND
  V13  MHA_DATA18  BI  = M_H_CPU0_SA_DQ<18>
  V14  MHA_DATA17  BI  = M_H_CPU0_SA_DQ<17>
  V15  VSS_V15  POWER  = GND
  V16  MJA_DATA18  BI  = M_J_CPU0_SA_DQ<18>
  V17  VSS_V17  POWER  = GND
  V18  MJA_DATA17  BI  = M_J_CPU0_SA_DQ<17>
  V19  VSS_V19  POWER  = GND
  V20  MIA_DATA18  BI  = M_I_CPU0_SA_DQ<18>
  V21  MIA_DATA17  BI  = M_I_CPU0_SA_DQ<17>
  V22  VDDCR_SOC_V22  POWER  = PVDDCR_SOC_P0
  V23  VSS_V23  POWER  = GND
  V24  VSS_V24  POWER  = GND
  V25  VSS_V25  POWER  = GND
  V26  VSS_V26  POWER  = GND
  V27  VSS_V27  POWER  = GND
  V28  VSS_V28  POWER  = GND
  V29  VSS_V29  POWER  = GND
  V30  VSS_V30  POWER  = GND
  V31  VSS_V31  POWER  = GND
  V32  VSS_V32  POWER  = GND
  V33  VSS_V33  POWER  = GND
  V34  VSS_V34  POWER  = GND
  V35  \g3_txp15||sata37_txp\  OUT  = P5E_CPU0_G3_TX_DP<15>
  V36  \g3_txn15||sata37_txn\  OUT  = P5E_CPU0_G3_TX_DN<15>
  V37  VSS_V37  POWER  = GND
  V39  VSS_V39  POWER  = GND
  V40  G1_RXN0  IN  = GMI_CPU1_G3_CPU0_G1_TX_DN<0>
  V41  G1_RXP0  IN  = GMI_CPU1_G3_CPU0_G1_TX_DP<0>
  V42  VSS_V42  POWER  = GND
  V43  VSS_V43  POWER  = GND
  V44  VSS_V44  POWER  = GND
  V45  VSS_V45  POWER  = GND
  V46  VSS_V46  POWER  = GND
  V47  VSS_V47  POWER  = GND
  V48  VSS_V48  POWER  = GND
  V49  VSS_V49  POWER  = GND
  V50  VSS_V50  POWER  = GND
  V51  VSS_V51  POWER  = GND
  V52  VSS_V52  POWER  = GND
  V53  VSS_V53  POWER  = GND
  V54  VDDIO_V54  POWER  = PVDDIO_P0
  V55  MCA_DATA17  BI  = M_C_CPU0_SA_DQ<17>
  V56  MCA_DATA18  BI  = M_C_CPU0_SA_DQ<18>
  V57  VSS_V57  POWER  = GND
  V58  MDA_DATA17  BI  = M_D_CPU0_SA_DQ<17>
  V59  VSS_V59  POWER  = GND
  V60  MDA_DATA18  BI  = M_D_CPU0_SA_DQ<18>
  V61  VSS_V61  POWER  = GND
  V62  MBA_DATA17  BI  = M_B_CPU0_SA_DQ<17>
  V63  MBA_DATA18  BI  = M_B_CPU0_SA_DQ<18>
  V64  VSS_V64  POWER  = GND
  V65  MFA_DATA17  BI  = M_F_CPU0_SA_DQ<17>
  V66  VSS_V66  POWER  = GND
  V67  MFA_DATA18  BI  = M_F_CPU0_SA_DQ<18>
  V68  VSS_V68  POWER  = GND
  V69  MEA_DATA17  BI  = M_E_CPU0_SA_DQ<17>
  V70  MEA_DATA18  BI  = M_E_CPU0_SA_DQ<18>
  V71  VSS_V71  POWER  = GND
  V72  MAA_DATA17  BI  = M_A_CPU0_SA_DQ<17>
  V73  VSS_V73  POWER  = GND
  V74  MAA_DATA18  BI  = M_A_CPU0_SA_DQ<18>
  W1  VSS_W1  POWER  = GND
  W2  MGA_DQS_H2  BI  = M_G_CPU0_SA_DQS_DP<2>
  W3  MGA_DATA19  BI  = M_G_CPU0_SA_DQ<19>
  W4  VSS_W4  POWER  = GND
  W5  MKA_DQS_H2  BI  = M_K_CPU0_SA_DQS_DP<2>
  W6  VSS_W6  POWER  = GND
  W7  MKA_DATA19  BI  = M_K_CPU0_SA_DQ<19>
  W8  VSS_W8  POWER  = GND
  W9  MLA_DQS_H2  BI  = M_L_CPU0_SA_DQS_DP<2>
  W10  MLA_DATA19  BI  = M_L_CPU0_SA_DQ<19>
  W11  VSS_W11  POWER  = GND
  W12  MHA_DQS_H2  BI  = M_H_CPU0_SA_DQS_DP<2>
  W13  VSS_W13  POWER  = GND
  W14  MHA_DATA19  BI  = M_H_CPU0_SA_DQ<19>
  W15  VSS_W15  POWER  = GND
  W16  MJA_DQS_H2  BI  = M_J_CPU0_SA_DQS_DP<2>
  W17  MJA_DATA19  BI  = M_J_CPU0_SA_DQ<19>
  W18  VSS_W18  POWER  = GND
  W19  MIA_DQS_H2  BI  = M_I_CPU0_SA_DQS_DP<2>
  W20  VSS_W20  POWER  = GND
  W21  MIA_DATA19  BI  = M_I_CPU0_SA_DQ<19>
  W22  VSS_W22  POWER  = GND
  W23  \g3_txp2||sata22_txp\  OUT  = P5E_CPU0_G3_TX_DP<2>
  W24  \g3_txn2||sata22_txn\  OUT  = P5E_CPU0_G3_TX_DN<2>
  W25  VSS_W25  POWER  = GND
  W26  \g3_txp6||sata26_txp\  OUT  = P5E_CPU0_G3_TX_DP<6>
  W27  \g3_txn6||sata26_txn\  OUT  = P5E_CPU0_G3_TX_DN<6>
  W28  VSS_W28  POWER  = GND
  W29  VDDCR_CPU0_W29  POWER  = PVDDCR_CPU0_P0
  W30  VDDCR_CPU0_W30  POWER  = PVDDCR_CPU0_P0
  W31  TEST41_IOD  TRI  = TP_CPU0_TEST41_IDO
  W32  VDDCR_CPU0_W32  POWER  = PVDDCR_CPU0_P0
  W33  VDDCR_CPU0_W33  POWER  = PVDDCR_CPU0_P0
  W34  VSS_W34  POWER  = GND
  W35  VSS_W35  POWER  = GND
  W36  VSS_W36  POWER  = GND
  W40  VSS_W40  POWER  = GND
  W41  VSS_W41  POWER  = GND
  W42  VSS_W42  POWER  = GND
  W43  VDDCR_CPU0_W43  POWER  = PVDDCR_CPU0_P0
  W44  VDDCR_CPU0_W44  POWER  = PVDDCR_CPU0_P0
  W45  VSS_W45  POWER  = GND
  W46  VDDCR_CPU0_W46  POWER  = PVDDCR_CPU0_P0
  W47  VDDCR_CPU0_W47  POWER  = PVDDCR_CPU0_P0
  W48  VSS_W48  POWER  = GND
  W49  G1_RXN9  IN  = GMI_CPU1_G3_CPU0_G1_TX_DN<9>
  W50  G1_RXP9  IN  = GMI_CPU1_G3_CPU0_G1_TX_DP<9>
  W51  VSS_W51  POWER  = GND
  W52  G1_RXN13  IN  = GMI_CPU1_G3_CPU0_G1_TX_DN<13>
  W53  G1_RXP13  IN  = GMI_CPU1_G3_CPU0_G1_TX_DP<13>
  W54  VSS_W54  POWER  = GND
  W55  MCA_DATA19  BI  = M_C_CPU0_SA_DQ<19>
  W56  VSS_W56  POWER  = GND
  W57  MCA_DQS_H2  BI  = M_C_CPU0_SA_DQS_DP<2>
  W58  VSS_W58  POWER  = GND
  W59  MDA_DATA19  BI  = M_D_CPU0_SA_DQ<19>
  W60  MDA_DQS_H2  BI  = M_D_CPU0_SA_DQS_DP<2>
  W61  VSS_W61  POWER  = GND
  W62  MBA_DATA19  BI  = M_B_CPU0_SA_DQ<19>
  W63  VSS_W63  POWER  = GND
  W64  MBA_DQS_H2  BI  = M_B_CPU0_SA_DQS_DP<2>
  W65  VSS_W65  POWER  = GND
  W66  MFA_DATA19  BI  = M_F_CPU0_SA_DQ<19>
  W67  MFA_DQS_H2  BI  = M_F_CPU0_SA_DQS_DP<2>
  W68  VSS_W68  POWER  = GND
  W69  MEA_DATA19  BI  = M_E_CPU0_SA_DQ<19>
  W70  VSS_W70  POWER  = GND
  W71  MEA_DQS_H2  BI  = M_E_CPU0_SA_DQS_DP<2>
  W72  VSS_W72  POWER  = GND
  W73  MAA_DATA19  BI  = M_A_CPU0_SA_DQ<19>
  W74  MAA_DQS_H2  BI  = M_A_CPU0_SA_DQS_DP<2>
  W75  VSS_W75  POWER  = GND
  Y2  MGA_DQS_L2  BI  = M_G_CPU0_SA_DQS_DN<2>
  Y3  VSS_Y3  POWER  = GND
  Y4  MGA_DQS_L7  BI  = M_G_CPU0_SA_DQS_DN<7>
  Y5  VDDCR_SOC_Y5  POWER  = PVDDCR_SOC_P0
  Y6  MKA_DQS_L2  BI  = M_K_CPU0_SA_DQS_DN<2>
  Y7  MKA_DQS_L7  BI  = M_K_CPU0_SA_DQS_DN<7>
  Y8  VSS_Y8  POWER  = GND
  Y9  MLA_DQS_L2  BI  = M_L_CPU0_SA_DQS_DN<2>
  Y10  VSS_Y10  POWER  = GND
  Y11  MLA_DQS_L7  BI  = M_L_CPU0_SA_DQS_DN<7>
  Y12  VDDCR_SOC_Y12  POWER  = PVDDCR_SOC_P0
  Y13  MHA_DQS_L2  BI  = M_H_CPU0_SA_DQS_DN<2>
  Y14  MHA_DQS_L7  BI  = M_H_CPU0_SA_DQS_DN<7>
  Y15  VSS_Y15  POWER  = GND
  Y16  MJA_DQS_L2  BI  = M_J_CPU0_SA_DQS_DN<2>
  Y17  VSS_Y17  POWER  = GND
  Y18  MJA_DQS_L7  BI  = M_J_CPU0_SA_DQS_DN<7>
  Y19  VDDCR_SOC_Y19  POWER  = PVDDCR_SOC_P0
  Y20  MIA_DQS_L2  BI  = M_I_CPU0_SA_DQS_DN<2>
  Y21  MIA_DQS_L7  BI  = M_I_CPU0_SA_DQS_DN<7>
  Y22  VSS_Y22  POWER  = GND
  Y23  VSS_Y23  POWER  = GND
  Y24  VSS_Y24  POWER  = GND
  Y25  VSS_Y25  POWER  = GND
